# S9S_MB_2U (Grand Teton) — schematic netlist excerpt (pin names and nets, part order shuffled) for the footprints in the layout excerpt that follows; sources: Cadence DE-HDL packaged netlist, KiCad conversion of 03242023_DA0F0TMBIJ0_F0T_Motherboard_J_brd_V01_OCP.brd

PC1659  Q_CAP  100NF 50V 10% X7R  pkg C0402  page 293 : A = P12V_AUX ; B = GND
C911  Q_CAP_DIFFBUS  DIFF BUS_0.22UF 6.3V 20% X6S  pkg C0201  page 173 : \1\ = P5E_CPU0_PE0_TX_C_DP<11> ; \2\ = P5E_CPU0_PE0_TX_DP<11>
PR4527  Q_RES  10M 1% CHIP  pkg 0402LF  page 192 : A = P3V3_E1S_0_R ; B = P3V3_E1S_GATE_0

(kicad_pcb
	(version 20260206)
	(generator "pcbnew")
	(generator_version "10.0")
	(general
		(thickness 1.6)
		(legacy_teardrops no)
	)
	(paper "A4")
	(title_block
		(title "03242023_DA0F0TMBIJ0_F0T_Motherboard_J_brd_V01_OCP.brd")
		(comment 1 "Grand Teton / footprints 2424-2426 of 6105")
	)
	(layers
		(0 "F.Cu" signal "TOP")
		(4 "In1.Cu" signal "GND")
		(6 "In2.Cu" signal "IN1")
		(8 "In3.Cu" signal "GND1")
		(10 "In4.Cu" signal "IN2")
		(12 "In5.Cu" signal "GND2")
		(14 "In6.Cu" signal "IN3")
		(16 "In7.Cu" signal "GND3")
		(18 "In8.Cu" signal "VCC")
		(20 "In9.Cu" signal "VCC1")
		(22 "In10.Cu" signal "GND4")
		(24 "In11.Cu" signal "IN4")
		(26 "In12.Cu" signal "GND5")
		(28 "In13.Cu" signal "IN5")
		(30 "In14.Cu" signal "GND6")
		(32 "In15.Cu" signal "IN6")
		(34 "In16.Cu" signal "GND7")
		(2 "B.Cu" signal "BOTTOM")
		(9 "F.Adhes" user "F.Adhesive")
		(11 "B.Adhes" user "B.Adhesive")
		(13 "F.Paste" user "Package Geometry/Pastemask Top")
		(15 "B.Paste" user "Package Geometry/Pastemask Bottom")
		(5 "F.SilkS" user "Ref Des/Silkscreen Top")
		(7 "B.SilkS" user "Ref Des/Silkscreen Bottom")
		(1 "F.Mask" user "Board Geometry/Soldermask Top")
		(3 "B.Mask" user "Board Geometry/Soldermask Bottom")
		(17 "Dwgs.User" user "User.Drawings")
		(19 "Cmts.User" user "User.Comments")
		(21 "Eco1.User" user "User.Eco1")
		(23 "Eco2.User" user "User.Eco2")
		(25 "Edge.Cuts" user "Board Geometry/Outline")
		(27 "Margin" user)
		(31 "F.CrtYd" user "Package Geometry/Place Bound Top")
		(29 "B.CrtYd" user "Package Geometry/Place Bound Bottom")
		(35 "F.Fab" user "Ref Des/Assembly Top")
		(33 "B.Fab" user "Ref Des/Assembly Bottom")
	)
	(footprint ""
		(layer "F.Cu")
		(at 223.384364 -75.86091 180)
		(property "Reference" "PR4527"
			(at 0 0 180)
			(layer "F.SilkS")
			(hide yes)
			(effects
				(font
					(size 1.27 1.27)
				)
			)
		)
		(property "Value" ""
			(at 0 0 180)
			(layer "F.Fab")
			(effects
				(font
					(size 1.27 1.27)
				)
			)
		)
		(duplicate_pad_numbers_are_jumpers no)
		(fp_line
			(start 0.7874 0.4064)
			(end -0.7874 0.4064)
			(stroke
				(width 0.1524)
				(type default)
			)
			(layer "F.SilkS")
		)
		(fp_line
			(start 0.7874 -0.4064)
			(end 0.7874 0.4064)
			(stroke
				(width 0.1524)
				(type default)
			)
			(layer "F.SilkS")
		)
		(fp_line
			(start -0.7874 0.4064)
			(end -0.7874 -0.4064)
			(stroke
				(width 0.1524)
				(type default)
			)
			(layer "F.SilkS")
		)
		(fp_line
			(start -0.7874 -0.4064)
			(end 0.7874 -0.4064)
			(stroke
				(width 0.1524)
				(type default)
			)
			(layer "F.SilkS")
		)
		(fp_line
			(start 0.67945 0.3048)
			(end 0.120396 0.3048)
			(stroke
				(width 0.1)
				(type default)
			)
			(layer "F.Fab")
		)
		(fp_line
			(start 0.67945 -0.3048)
			(end 0.67945 0.3048)
			(stroke
				(width 0.1)
				(type default)
			)
			(layer "F.Fab")
		)
		(fp_line
			(start 0.12065 -0.2794)
			(end 0.12065 -0.3048)
			(stroke
				(width 0.1)
				(type default)
			)
			(layer "F.Fab")
		)
		(fp_line
			(start 0.12065 -0.3048)
			(end 0.67945 -0.3048)
			(stroke
				(width 0.1)
				(type default)
			)
			(layer "F.Fab")
		)
		(fp_line
			(start 0.120396 0.3048)
			(end 0.120396 0.2794)
			(stroke
				(width 0.1)
				(type default)
			)
			(layer "F.Fab")
		)
		(fp_line
			(start 0.120396 0.2794)
			(end -0.12065 0.2794)
			(stroke
				(width 0.1)
				(type default)
			)
			(layer "F.Fab")
		)
		(fp_line
			(start -0.12065 0.3048)
			(end -0.67945 0.3048)
			(stroke
				(width 0.1)
				(type default)
			)
			(layer "F.Fab")
		)
		(fp_line
			(start -0.12065 0.2794)
			(end -0.12065 0.3048)
			(stroke
				(width 0.1)
				(type default)
			)
			(layer "F.Fab")
		)
		(fp_line
			(start -0.12065 -0.2794)
			(end 0.12065 -0.2794)
			(stroke
				(width 0.1)
				(type default)
			)
			(layer "F.Fab")
		)
		(fp_line
			(start -0.12065 -0.305054)
			(end -0.12065 -0.2794)
			(stroke
				(width 0.1)
				(type default)
			)
			(layer "F.Fab")
		)
		(fp_line
			(start -0.67945 0.3048)
			(end -0.67945 -0.305054)
			(stroke
				(width 0.1)
				(type default)
			)
			(layer "F.Fab")
		)
		(fp_line
			(start -0.67945 -0.305054)
			(end -0.12065 -0.305054)
			(stroke
				(width 0.1)
				(type default)
			)
			(layer "F.Fab")
		)
		(pad "1" smd circle
			(at -0.40005 0 180)
			(size 0 0)
			(layers "F.Cu" "F.Mask" "F.Paste")
			(net "P3V3_E1S_0_R")
		)
		(pad "2" smd circle
			(at 0.40005 0 180)
			(size 0 0)
			(layers "F.Cu" "F.Mask" "F.Paste")
			(net "P3V3_E1S_GATE_0")
		)
	)
	(footprint ""
		(layer "F.Cu")
		(at 318.468248 -408.517344 -90)
		(property "Reference" "C911"
			(at 0 0 270)
			(layer "F.SilkS")
			(hide yes)
			(effects
				(font
					(size 1.27 1.27)
				)
			)
		)
		(property "Value" ""
			(at 0 0 270)
			(layer "F.Fab")
			(effects
				(font
					(size 1.27 1.27)
				)
			)
		)
		(duplicate_pad_numbers_are_jumpers no)
		(fp_line
			(start -0.299974 0.150114)
			(end -0.299974 -0.150114)
			(stroke
				(width 0.1)
				(type default)
			)
			(layer "F.Fab")
		)
		(fp_line
			(start 0.299974 0.150114)
			(end -0.299974 0.150114)
			(stroke
				(width 0.1)
				(type default)
			)
			(layer "F.Fab")
		)
		(fp_line
			(start -0.299974 -0.150114)
			(end 0.299974 -0.150114)
			(stroke
				(width 0.1)
				(type default)
			)
			(layer "F.Fab")
		)
		(fp_line
			(start 0.299974 -0.150114)
			(end 0.299974 0.150114)
			(stroke
				(width 0.1)
				(type default)
			)
			(layer "F.Fab")
		)
		(pad "1" smd rect
			(at -0.2667 0 270)
			(size 0.3048 0.381)
			(layers "F.Cu" "F.Mask" "F.Paste")
			(net "P5E_CPU0_PE0_TX_C_DP<11>")
		)
		(pad "2" smd rect
			(at 0.2667 0 270)
			(size 0.3048 0.381)
			(layers "F.Cu" "F.Mask" "F.Paste")
			(net "P5E_CPU0_PE0_TX_DP<11>")
		)
	)
	(footprint ""
		(layer "F.Cu")
		(at 48.28794 -145.026888 -90)
		(property "Reference" "PC1659"
			(at 0 0 270)
			(layer "F.SilkS")
			(hide yes)
			(effects
				(font
					(size 1.27 1.27)
				)
			)
		)
		(property "Value" ""
			(at 0 0 270)
			(layer "F.Fab")
			(effects
				(font
					(size 1.27 1.27)
				)
			)
		)
		(duplicate_pad_numbers_are_jumpers no)
		(fp_line
			(start -0.7874 0.4064)
			(end -0.7874 -0.4064)
			(stroke
				(width 0.1524)
				(type default)
			)
			(layer "F.SilkS")
		)
		(fp_line
			(start 0.7874 0.4064)
			(end -0.7874 0.4064)
			(stroke
				(width 0.1524)
				(type default)
			)
			(layer "F.SilkS")
		)
		(fp_line
			(start -0.7874 -0.4064)
			(end 0.7874 -0.4064)
			(stroke
				(width 0.1524)
				(type default)
			)
			(layer "F.SilkS")
		)
		(fp_line
			(start 0.7874 -0.4064)
			(end 0.7874 0.4064)
			(stroke
				(width 0.1524)
				(type default)
			)
			(layer "F.SilkS")
		)
		(fp_line
			(start -0.67945 0.3048)
			(end -0.67945 -0.305054)
			(stroke
				(width 0.1)
				(type default)
			)
			(layer "F.Fab")
		)
		(fp_line
			(start -0.12065 0.3048)
			(end -0.67945 0.3048)
			(stroke
				(width 0.1)
				(type default)
			)
			(layer "F.Fab")
		)
		(fp_line
			(start 0.120396 0.3048)
			(end 0.120396 0.2794)
			(stroke
				(width 0.1)
				(type default)
			)
			(layer "F.Fab")
		)
		(fp_line
			(start 0.67945 0.3048)
			(end 0.120396 0.3048)
			(stroke
				(width 0.1)
				(type default)
			)
			(layer "F.Fab")
		)
		(fp_line
			(start -0.12065 0.2794)
			(end -0.12065 0.3048)
			(stroke
				(width 0.1)
				(type default)
			)
			(layer "F.Fab")
		)
		(fp_line
			(start 0.120396 0.2794)
			(end -0.12065 0.2794)
			(stroke
				(width 0.1)
				(type default)
			)
			(layer "F.Fab")
		)
		(fp_line
			(start -0.12065 -0.2794)
			(end 0.12065 -0.2794)
			(stroke
				(width 0.1)
				(type default)
			)
			(layer "F.Fab")
		)
		(fp_line
			(start 0.12065 -0.2794)
			(end 0.12065 -0.3048)
			(stroke
				(width 0.1)
				(type default)
			)
			(layer "F.Fab")
		)
		(fp_line
			(start 0.12065 -0.3048)
			(end 0.67945 -0.3048)
			(stroke
				(width 0.1)
				(type default)
			)
			(layer "F.Fab")
		)
		(fp_line
			(start 0.67945 -0.3048)
			(end 0.67945 0.3048)
			(stroke
				(width 0.1)
				(type default)
			)
			(layer "F.Fab")
		)
		(fp_line
			(start -0.67945 -0.305054)
			(end -0.12065 -0.305054)
			(stroke
				(width 0.1)
				(type default)
			)
			(layer "F.Fab")
		)
		(fp_line
			(start -0.12065 -0.305054)
			(end -0.12065 -0.2794)
			(stroke
				(width 0.1)
				(type default)
			)
			(layer "F.Fab")
		)
		(pad "1" smd circle
			(at -0.40005 0 270)
			(size 0 0)
			(layers "F.Cu" "F.Mask" "F.Paste")
			(net "P12V_AUX")
		)
		(pad "2" smd circle
			(at 0.40005 0 270)
			(size 0 0)
			(layers "F.Cu" "F.Mask" "F.Paste")
			(net "GND")
		)
	)
)
